FILE_TYPE = CONNECTIVITY;
{Allegro Design Entry HDL 17.2-2016 S081 (4005846) 1/11/2022}
"PAGE_NUMBER" = 151;
0"NC";
1"PVDD18_S5_P0\g";
2"GND\g";
3"GND\g";
4"GND\g";
5"GND\g";
6"PVDD18_S5_P0\g";
7"PVDD18_S5_P0\g";
8"GND\g";
9"GND\g";
10"GND\g";
11"GND\g";
12"GND\g";
13"GND\g";
14"GND\g";
15"PVDD18_S5_P0\g";
16"CPU0_HDT_BYPASS_SEL";
17"CPU1_HDT_BYPASS_SEL";
18"FM_PLD_CPU0_PRSNT_HDT_N";
19"JTAG_CPUX_TDI";
20"JTAG_CPU0_TDO";
21"JTAG_CPU0_BYPASS";
22"JTAG_CPU0_R_TDI";
23"JTAG_CPU0_TDO_CPU1_TDI";
24"PVDD18_S5_P0\g";
25"JTAG_CPU0_TDI";
26"PVDD18_S5_P0\g";
27"FM_PLD_CPU1_PRSNT_HDT_N";
28"JTAG_CPU1_TDO";
29"JTAG_CPUX_TDO";
30"PVDD18_S5_P0\g";
31"JTAG_CPU1_BYPASS";
32"JTAG_CPU1_R_TDI";
33"PVDD18_S5_P0\g";
34"JTAG_CPU1_TDI";
%"SN74AUC2G66DCTR"
"1","(-6375,5800)","0","pure_quanta","I1";
;
LOCATION"U153"
$SEC"1"
CDS_SEC"1"
PART_TYPE"SMLF"
MATERIAL"IC"
VALUE"SN74AUC2G66DCTR"
PART_NUMBER"AL2G0066C00"
CDS_LMAN_SYM_OUTLINE"-150,125,150,-125"
NEEDS_NO_SIZE"TRUE"
CDS_LIB"pure_quanta";
"2B"
$PN"6"21;
"1B"
$PN"2"22;
"GND"
$PN"4"2;
"VCC"
$PN"8"26;
"2C"
$PN"3"18;
"2A"
$PN"5"19;
"1C"
$PN"7"16;
"1A"
$PN"1"19;
%"Q_RES"
"2","(-8200,5325)","2","pure_quanta","I10";
;
LOCATION"R1646"
$SEC"1"
CDS_SEC"1"
WATTAGE"1/16W"
MATERIAL"CHIP"
TOLERANCE"1%"
VALUE"1K"
PART_NUMBER"TMP_QCS21002FB24"
PACK_TYPE"0402LF"
CDS_LIB"pure_quanta";
"A"
$PN"1"15;
"B"
$PN"2"16;
%"Q_RES"
"2","(-7600,5500)","0","pure_quanta","I11";
;
LOCATION"R1647"
$SEC"1"
CDS_SEC"1"
WATTAGE"1/16W"
MATERIAL"CHIP"
TOLERANCE"1%"
VALUE"1K"
PART_NUMBER"TMP_QCS21002FB24"
PACK_TYPE"0402LF"
CDS_LIB"pure_quanta";
"A"
$PN"1"1;
"B"
$PN"2"18;
%"UNIVERSAL_POWER"
"1","(-7600,5700)","0","pure_quanta_power","I12";
;
HDL_POWER"PVDD18_S5_P0"
CDS_LIB"pure_quanta_power";
"A"1;
%"GND"
"1","(-5975,5600)","0","pure_quanta_power","I13";
;
CDS_LIB"pure_quanta_power"
SIZE"1B"
HDL_POWER"GND";
"A<SIZE-1..0>\NAC"2;
%"GND"
"1","(-5725,5925)","0","pure_quanta_power","I14";
;
CDS_LIB"pure_quanta_power"
SIZE"1B"
HDL_POWER"GND";
"A<SIZE-1..0>\NAC"3;
%"Q_CAP"
"1","(-5725,6125)","0","pure_quanta","I15";
;
LOCATION"C1519"
$SEC"1"
CDS_SEC"1"
MATERIAL"X7R"
TOLERANCE"10%"
VALUE"0.1UF"
PART_NUMBER"CH4103K1B08"
VOLTAGE"16V"
PACK_TYPE"C0402"
CDS_LIB"pure_quanta";
"B"
$PN"2"3;
"A"
$PN"1"26;
%"UNIVERSAL_POWER"
"1","(-5950,6400)","0","pure_quanta_power","I16";
;
HDL_POWER"PVDD18_S5_P0"
CDS_LIB"pure_quanta_power";
"A"26;
%"SN74AUC2G66DCTR"
"1","(-4975,4450)","0","pure_quanta","I17";
;
LOCATION"U13"
SEC"1"
PART_TYPE"SMLF"
MATERIAL"IC"
VALUE"SN74AUC2G66DCTR"
PART_NUMBER"AL2G0066C00"
SEC_TYPE""
NEEDS_NO_SIZE"TRUE"
CDS_LMAN_SYM_OUTLINE"-150,125,150,-125"
CDS_LIB"pure_quanta";
"2B"
$PN"6"23;
"1B"
$PN"2"23;
"GND"
$PN"4"11;
"VCC"
$PN"8"24;
"2C"
$PN"3"18;
"2A"
$PN"5"21;
"1C"
$PN"7"16;
"1A"
$PN"1"20;
%"GND"
"1","(-7600,4650)","0","pure_quanta_power","I19";
;
CDS_LIB"pure_quanta_power"
SIZE"1B"
HDL_POWER"GND";
"A<SIZE-1..0>\NAC"4;
%"Q_RES"
"1","(-5225,5825)","0","pure_quanta","I2";
;
LOCATION"R1648"
$SEC"1"
CDS_SEC"1"
MATERIAL"CHIP"
TOLERANCE"1%"
VALUE"22"
CDS_LIB"pure_quanta"
WATTAGE"1/16W"
PART_NUMBER"CS02202FB12"
PACK_TYPE"0402LF";
"B"
$PN"2"25;
"A"
$PN"1"22;
%"UNIVERSAL_POWER"
"1","(-4225,5050)","0","pure_quanta_power","I20";
;
HDL_POWER"PVDD18_S5_P0"
CDS_LIB"pure_quanta_power";
"A"24;
%"GND"
"1","(-4000,4575)","0","pure_quanta_power","I21";
;
CDS_LIB"pure_quanta_power"
SIZE"1B"
HDL_POWER"GND";
"A<SIZE-1..0>\NAC"5;
%"Q_CAP"
"1","(-4000,4775)","0","pure_quanta","I22";
;
LOCATION"C1521"
$SEC"1"
CDS_SEC"1"
MATERIAL"X7R"
TOLERANCE"10%"
VALUE"0.1UF"
PART_NUMBER"CH4103K1B08"
VOLTAGE"16V"
PACK_TYPE"C0402"
CDS_LIB"pure_quanta";
"B"
$PN"2"5;
"A"
$PN"1"24;
%"SN74AUC2G66DCTR"
"1","(-3125,4400)","0","pure_quanta","I23";
;
LOCATION"U14"
SEC"1"
PART_TYPE"SMLF"
MATERIAL"IC"
VALUE"SN74AUC2G66DCTR"
PART_NUMBER"AL2G0066C00"
SEC_TYPE""
CDS_LMAN_SYM_OUTLINE"-150,125,150,-125"
NEEDS_NO_SIZE"TRUE"
CDS_LIB"pure_quanta";
"2B"
$PN"6"31;
"1B"
$PN"2"32;
"GND"
$PN"4"12;
"VCC"
$PN"8"33;
"2C"
$PN"3"27;
"2A"
$PN"5"23;
"1C"
$PN"7"17;
"1A"
$PN"1"23;
%"Q_RES"
"2","(-5225,3400)","2","pure_quanta","I25";
;
LOCATION"R1649"
$SEC"1"
CDS_SEC"1"
WATTAGE"1/16W"
MATERIAL"CHIP"
TOLERANCE"1%"
VALUE"1K"
PART_NUMBER"TMP_QCS21002FB24"
PACK_TYPE"0402LF"
CDS_LIB"pure_quanta";
"A"
$PN"1"7;
"B"
$PN"2"17;
%"UNIVERSAL_POWER"
"1","(-4550,3725)","0","pure_quanta_power","I26";
;
HDL_POWER"PVDD18_S5_P0"
CDS_LIB"pure_quanta_power";
"A"6;
%"Q_RES"
"2","(-4550,3525)","0","pure_quanta","I27";
;
LOCATION"R1650"
$SEC"1"
CDS_SEC"1"
WATTAGE"1/16W"
MATERIAL"CHIP"
TOLERANCE"1%"
VALUE"1K"
PART_NUMBER"TMP_QCS21002FB24"
PACK_TYPE"0402LF"
CDS_LIB"pure_quanta";
"A"
$PN"1"6;
"B"
$PN"2"27;
%"UNIVERSAL_POWER"
"1","(-5225,3650)","0","pure_quanta_power","I28";
;
HDL_POWER"PVDD18_S5_P0"
CDS_LIB"pure_quanta_power";
"A"7;
%"GND"
"1","(-4550,2725)","0","pure_quanta_power","I29";
;
CDS_LIB"pure_quanta_power"
SIZE"1B"
HDL_POWER"GND";
"A<SIZE-1..0>\NAC"8;
%"GND"
"1","(-4900,5325)","0","pure_quanta_power","I3";
;
SIZE"1B"
CDS_LIB"pure_quanta_power"
HDL_POWER"GND";
"A<SIZE-1..0>\NAC"9;
%"SN74AUC2G66DCTR"
"1","(-1850,3400)","0","pure_quanta","I31";
;
LOCATION"U154"
$SEC"1"
CDS_SEC"1"
PART_TYPE"SMLF"
MATERIAL"IC"
VALUE"SN74AUC2G66DCTR"
PART_NUMBER"AL2G0066C00"
NEEDS_NO_SIZE"TRUE"
CDS_LMAN_SYM_OUTLINE"-150,125,150,-125"
CDS_LIB"pure_quanta";
"2B"
$PN"6"29;
"1B"
$PN"2"29;
"GND"
$PN"4"13;
"VCC"
$PN"8"30;
"2C"
$PN"3"27;
"2A"
$PN"5"31;
"1C"
$PN"7"17;
"1A"
$PN"1"28;
%"Q_RES"
"1","(-1975,4425)","0","pure_quanta","I34";
;
LOCATION"R1651"
$SEC"1"
CDS_SEC"1"
MATERIAL"CHIP"
TOLERANCE"1%"
VALUE"22"
CDS_LIB"pure_quanta"
WATTAGE"1/16W"
PART_NUMBER"CS02202FB12"
PACK_TYPE"0402LF";
"B"
$PN"2"34;
"A"
$PN"1"32;
%"UNIVERSAL_POWER"
"1","(-2375,5000)","0","pure_quanta_power","I35";
;
HDL_POWER"PVDD18_S5_P0"
CDS_LIB"pure_quanta_power";
"A"33;
%"Q_CAP"
"1","(-2150,4725)","0","pure_quanta","I36";
;
LOCATION"C1522"
$SEC"1"
CDS_SEC"1"
MATERIAL"X7R"
TOLERANCE"10%"
VALUE"0.1UF"
PART_NUMBER"CH4103K1B08"
VOLTAGE"16V"
PACK_TYPE"C0402"
CDS_LIB"pure_quanta";
"B"
$PN"2"10;
"A"
$PN"1"33;
%"GND"
"1","(-2150,4525)","0","pure_quanta_power","I37";
;
SIZE"1B"
CDS_LIB"pure_quanta_power"
HDL_POWER"GND";
"A<SIZE-1..0>\NAC"10;
%"GND"
"1","(-4575,4250)","0","pure_quanta_power","I38";
;
CDS_LIB"pure_quanta_power"
SIZE"1B"
HDL_POWER"GND";
"A<SIZE-1..0>\NAC"11;
%"GND"
"1","(-2725,4200)","0","pure_quanta_power","I39";
;
CDS_LIB"pure_quanta_power"
SIZE"1B"
HDL_POWER"GND";
"A<SIZE-1..0>\NAC"12;
%"Q_CAP"
"1","(-4900,5625)","0","pure_quanta","I4";
;
LOCATION"C1520"
$SEC"1"
CDS_SEC"1"
MATERIAL"EMPTY"
TOLERANCE"10%"
VALUE"0.01UF"
PART_NUMBER"CH31006KB18"
VOLTAGE"50V"
PACK_TYPE"C0402"
CDS_LIB"pure_quanta";
"B"
$PN"2"9;
"A"
$PN"1"25;
%"GND"
"1","(-1450,3200)","0","pure_quanta_power","I40";
;
SIZE"1B"
CDS_LIB"pure_quanta_power"
HDL_POWER"GND";
"A<SIZE-1..0>\NAC"13;
%"Q_CAP"
"1","(-1000,3750)","0","pure_quanta","I42";
;
LOCATION"C1523"
$SEC"1"
CDS_SEC"1"
MATERIAL"X7R"
TOLERANCE"10%"
VALUE"0.1UF"
PART_NUMBER"CH4103K1B08"
VOLTAGE"16V"
PACK_TYPE"C0402"
CDS_LIB"pure_quanta";
"B"
$PN"2"14;
"A"
$PN"1"30;
%"GND"
"1","(-1000,3550)","0","pure_quanta_power","I43";
;
CDS_LIB"pure_quanta_power"
SIZE"1B"
HDL_POWER"GND";
"A<SIZE-1..0>\NAC"14;
%"UNIVERSAL_POWER"
"1","(-1225,4025)","0","pure_quanta_power","I44";
;
HDL_POWER"PVDD18_S5_P0"
CDS_LIB"pure_quanta_power";
"A"30;
%"MOSFET_N"
"1","(-7650,5075)","0","pure_quanta","I45";
;
LOCATION"Q63"
$SEC"1"
CDS_SEC"1"
PART_TYPE"SMLF"
MATERIAL"IC"
VALUE"BSS138K"
PART_NUMBER"BAM138K0000"
MANUF_PN"BSS138K"
CDS_LMAN_SYM_OUTLINE"-50,50,100,-150"
CDS_LIB"pure_quanta"
PACK_TYPE"SMLF";
"GATE"
$PN"G"16;
"SOURCE"
$PN"S"4;
"DRAIN"
$PN"D"18;
%"MOSFET_N"
"1","(-4600,3150)","0","pure_quanta","I46";
;
LOCATION"Q64"
$SEC"1"
CDS_SEC"1"
PART_TYPE"SMLF"
MATERIAL"IC"
VALUE"BSS138K"
PART_NUMBER"BAM138K0000"
MANUF_PN"BSS138K"
CDS_LIB"pure_quanta"
CDS_LMAN_SYM_OUTLINE"-50,50,100,-150"
PACK_TYPE"SMLF";
"GATE"
$PN"G"17;
"SOURCE"
$PN"S"8;
"DRAIN"
$PN"D"27;
%"UNIVERSAL_POWER"
"1","(-8200,5575)","0","pure_quanta_power","I9";
;
HDL_POWER"PVDD18_S5_P0"
CDS_LIB"pure_quanta_power";
"A"15;
END.
